# S9S_MB_2U (Grand Teton) — schematic netlist excerpt (pin names and nets, part order shuffled) for the footprints in the layout excerpt that follows; sources: Cadence DE-HDL packaged netlist, KiCad conversion of 03242023_DA0F0TMBIJ0_F0T_Motherboard_J_brd_V01_OCP.brd

R1387  Q_RES  2K 1% EMPTY  pkg 0402LF  page 241 : A = SMB_SML1_PMBUS_3V3AUX_PCH_SDA ; B = P3V3_AUX
C1226  Q_CAP  0.22UF 25V 10% X7R  pkg C0402  page 260 : A = VR_P5V_EN_D_R ; B = GND
C693  Q_CAP_DIFFBUS  DIFF BUS_0.22UF 6.3V 20% X6S  pkg C0201  page 177 : \1\ = P5E_CPU1_PE4_TX_C_DP<8> ; \2\ = P5E_CPU1_PE4_TX_DP<8>

(kicad_pcb
	(version 20260206)
	(generator "pcbnew")
	(generator_version "10.0")
	(general
		(thickness 1.6)
		(legacy_teardrops no)
	)
	(paper "A4")
	(title_block
		(title "03242023_DA0F0TMBIJ0_F0T_Motherboard_J_brd_V01_OCP.brd")
		(comment 1 "Grand Teton / footprints 1953-1955 of 6105")
	)
	(layers
		(0 "F.Cu" signal "TOP")
		(4 "In1.Cu" signal "GND")
		(6 "In2.Cu" signal "IN1")
		(8 "In3.Cu" signal "GND1")
		(10 "In4.Cu" signal "IN2")
		(12 "In5.Cu" signal "GND2")
		(14 "In6.Cu" signal "IN3")
		(16 "In7.Cu" signal "GND3")
		(18 "In8.Cu" signal "VCC")
		(20 "In9.Cu" signal "VCC1")
		(22 "In10.Cu" signal "GND4")
		(24 "In11.Cu" signal "IN4")
		(26 "In12.Cu" signal "GND5")
		(28 "In13.Cu" signal "IN5")
		(30 "In14.Cu" signal "GND6")
		(32 "In15.Cu" signal "IN6")
		(34 "In16.Cu" signal "GND7")
		(2 "B.Cu" signal "BOTTOM")
		(9 "F.Adhes" user "F.Adhesive")
		(11 "B.Adhes" user "B.Adhesive")
		(13 "F.Paste" user "Package Geometry/Pastemask Top")
		(15 "B.Paste" user "Package Geometry/Pastemask Bottom")
		(5 "F.SilkS" user "Ref Des/Silkscreen Top")
		(7 "B.SilkS" user "Ref Des/Silkscreen Bottom")
		(1 "F.Mask" user "Board Geometry/Soldermask Top")
		(3 "B.Mask" user "Board Geometry/Soldermask Bottom")
		(17 "Dwgs.User" user "User.Drawings")
		(19 "Cmts.User" user "User.Comments")
		(21 "Eco1.User" user "User.Eco1")
		(23 "Eco2.User" user "User.Eco2")
		(25 "Edge.Cuts" user "Board Geometry/Outline")
		(27 "Margin" user)
		(31 "F.CrtYd" user "Package Geometry/Place Bound Top")
		(29 "B.CrtYd" user "Package Geometry/Place Bound Bottom")
		(35 "F.Fab" user "Ref Des/Assembly Top")
		(33 "B.Fab" user "Ref Des/Assembly Bottom")
	)
	(footprint ""
		(layer "F.Cu")
		(at 166.351458 -133.77672 90)
		(property "Reference" "C1226"
			(at 0 0 90)
			(layer "F.SilkS")
			(hide yes)
			(effects
				(font
					(size 1.27 1.27)
				)
			)
		)
		(property "Value" ""
			(at 0 0 90)
			(layer "F.Fab")
			(effects
				(font
					(size 1.27 1.27)
				)
			)
		)
		(duplicate_pad_numbers_are_jumpers no)
		(fp_line
			(start 0.7874 -0.4064)
			(end 0.7874 0.4064)
			(stroke
				(width 0.1524)
				(type default)
			)
			(layer "F.SilkS")
		)
		(fp_line
			(start -0.7874 -0.4064)
			(end 0.7874 -0.4064)
			(stroke
				(width 0.1524)
				(type default)
			)
			(layer "F.SilkS")
		)
		(fp_line
			(start 0.7874 0.4064)
			(end -0.7874 0.4064)
			(stroke
				(width 0.1524)
				(type default)
			)
			(layer "F.SilkS")
		)
		(fp_line
			(start -0.7874 0.4064)
			(end -0.7874 -0.4064)
			(stroke
				(width 0.1524)
				(type default)
			)
			(layer "F.SilkS")
		)
		(fp_line
			(start -0.12065 -0.305054)
			(end -0.12065 -0.2794)
			(stroke
				(width 0.1)
				(type default)
			)
			(layer "F.Fab")
		)
		(fp_line
			(start -0.67945 -0.305054)
			(end -0.12065 -0.305054)
			(stroke
				(width 0.1)
				(type default)
			)
			(layer "F.Fab")
		)
		(fp_line
			(start 0.67945 -0.3048)
			(end 0.67945 0.3048)
			(stroke
				(width 0.1)
				(type default)
			)
			(layer "F.Fab")
		)
		(fp_line
			(start 0.12065 -0.3048)
			(end 0.67945 -0.3048)
			(stroke
				(width 0.1)
				(type default)
			)
			(layer "F.Fab")
		)
		(fp_line
			(start 0.12065 -0.2794)
			(end 0.12065 -0.3048)
			(stroke
				(width 0.1)
				(type default)
			)
			(layer "F.Fab")
		)
		(fp_line
			(start -0.12065 -0.2794)
			(end 0.12065 -0.2794)
			(stroke
				(width 0.1)
				(type default)
			)
			(layer "F.Fab")
		)
		(fp_line
			(start 0.120396 0.2794)
			(end -0.12065 0.2794)
			(stroke
				(width 0.1)
				(type default)
			)
			(layer "F.Fab")
		)
		(fp_line
			(start -0.12065 0.2794)
			(end -0.12065 0.3048)
			(stroke
				(width 0.1)
				(type default)
			)
			(layer "F.Fab")
		)
		(fp_line
			(start 0.67945 0.3048)
			(end 0.120396 0.3048)
			(stroke
				(width 0.1)
				(type default)
			)
			(layer "F.Fab")
		)
		(fp_line
			(start 0.120396 0.3048)
			(end 0.120396 0.2794)
			(stroke
				(width 0.1)
				(type default)
			)
			(layer "F.Fab")
		)
		(fp_line
			(start -0.12065 0.3048)
			(end -0.67945 0.3048)
			(stroke
				(width 0.1)
				(type default)
			)
			(layer "F.Fab")
		)
		(fp_line
			(start -0.67945 0.3048)
			(end -0.67945 -0.305054)
			(stroke
				(width 0.1)
				(type default)
			)
			(layer "F.Fab")
		)
		(pad "1" smd circle
			(at -0.40005 0 90)
			(size 0 0)
			(layers "F.Cu" "F.Mask" "F.Paste")
			(net "VR_P5V_EN_D_R")
		)
		(pad "2" smd circle
			(at 0.40005 0 90)
			(size 0 0)
			(layers "F.Cu" "F.Mask" "F.Paste")
			(net "GND")
		)
	)
	(footprint ""
		(layer "F.Cu")
		(at 178.816 -19.776948 90)
		(property "Reference" "R1387"
			(at 0 0 90)
			(layer "F.SilkS")
			(hide yes)
			(effects
				(font
					(size 1.27 1.27)
				)
			)
		)
		(property "Value" ""
			(at 0 0 90)
			(layer "F.Fab")
			(effects
				(font
					(size 1.27 1.27)
				)
			)
		)
		(duplicate_pad_numbers_are_jumpers no)
		(fp_line
			(start 0.7874 -0.4064)
			(end 0.7874 0.4064)
			(stroke
				(width 0.1524)
				(type default)
			)
			(layer "F.SilkS")
		)
		(fp_line
			(start -0.7874 -0.4064)
			(end 0.7874 -0.4064)
			(stroke
				(width 0.1524)
				(type default)
			)
			(layer "F.SilkS")
		)
		(fp_line
			(start 0.7874 0.4064)
			(end -0.7874 0.4064)
			(stroke
				(width 0.1524)
				(type default)
			)
			(layer "F.SilkS")
		)
		(fp_line
			(start -0.7874 0.4064)
			(end -0.7874 -0.4064)
			(stroke
				(width 0.1524)
				(type default)
			)
			(layer "F.SilkS")
		)
		(fp_line
			(start -0.12065 -0.305054)
			(end -0.12065 -0.2794)
			(stroke
				(width 0.1)
				(type default)
			)
			(layer "F.Fab")
		)
		(fp_line
			(start -0.67945 -0.305054)
			(end -0.12065 -0.305054)
			(stroke
				(width 0.1)
				(type default)
			)
			(layer "F.Fab")
		)
		(fp_line
			(start 0.67945 -0.3048)
			(end 0.67945 0.3048)
			(stroke
				(width 0.1)
				(type default)
			)
			(layer "F.Fab")
		)
		(fp_line
			(start 0.12065 -0.3048)
			(end 0.67945 -0.3048)
			(stroke
				(width 0.1)
				(type default)
			)
			(layer "F.Fab")
		)
		(fp_line
			(start 0.12065 -0.2794)
			(end 0.12065 -0.3048)
			(stroke
				(width 0.1)
				(type default)
			)
			(layer "F.Fab")
		)
		(fp_line
			(start -0.12065 -0.2794)
			(end 0.12065 -0.2794)
			(stroke
				(width 0.1)
				(type default)
			)
			(layer "F.Fab")
		)
		(fp_line
			(start 0.120396 0.2794)
			(end -0.12065 0.2794)
			(stroke
				(width 0.1)
				(type default)
			)
			(layer "F.Fab")
		)
		(fp_line
			(start -0.12065 0.2794)
			(end -0.12065 0.3048)
			(stroke
				(width 0.1)
				(type default)
			)
			(layer "F.Fab")
		)
		(fp_line
			(start 0.67945 0.3048)
			(end 0.120396 0.3048)
			(stroke
				(width 0.1)
				(type default)
			)
			(layer "F.Fab")
		)
		(fp_line
			(start 0.120396 0.3048)
			(end 0.120396 0.2794)
			(stroke
				(width 0.1)
				(type default)
			)
			(layer "F.Fab")
		)
		(fp_line
			(start -0.12065 0.3048)
			(end -0.67945 0.3048)
			(stroke
				(width 0.1)
				(type default)
			)
			(layer "F.Fab")
		)
		(fp_line
			(start -0.67945 0.3048)
			(end -0.67945 -0.305054)
			(stroke
				(width 0.1)
				(type default)
			)
			(layer "F.Fab")
		)
		(pad "1" smd circle
			(at -0.40005 0 90)
			(size 0 0)
			(layers "F.Cu" "F.Mask" "F.Paste")
			(net "SMB_SML1_PMBUS_3V3AUX_PCH_SDA")
		)
		(pad "2" smd circle
			(at 0.40005 0 90)
			(size 0 0)
			(layers "F.Cu" "F.Mask" "F.Paste")
			(net "P3V3_AUX")
		)
	)
	(footprint ""
		(layer "F.Cu")
		(at 74.720958 -408.517344 -90)
		(property "Reference" "C693"
			(at 0 0 270)
			(layer "F.SilkS")
			(hide yes)
			(effects
				(font
					(size 1.27 1.27)
				)
			)
		)
		(property "Value" ""
			(at 0 0 270)
			(layer "F.Fab")
			(effects
				(font
					(size 1.27 1.27)
				)
			)
		)
		(duplicate_pad_numbers_are_jumpers no)
		(fp_line
			(start -0.299974 0.150114)
			(end -0.299974 -0.150114)
			(stroke
				(width 0.1)
				(type default)
			)
			(layer "F.Fab")
		)
		(fp_line
			(start 0.299974 0.150114)
			(end -0.299974 0.150114)
			(stroke
				(width 0.1)
				(type default)
			)
			(layer "F.Fab")
		)
		(fp_line
			(start -0.299974 -0.150114)
			(end 0.299974 -0.150114)
			(stroke
				(width 0.1)
				(type default)
			)
			(layer "F.Fab")
		)
		(fp_line
			(start 0.299974 -0.150114)
			(end 0.299974 0.150114)
			(stroke
				(width 0.1)
				(type default)
			)
			(layer "F.Fab")
		)
		(pad "1" smd rect
			(at -0.2667 0 270)
			(size 0.3048 0.381)
			(layers "F.Cu" "F.Mask" "F.Paste")
			(net "P5E_CPU1_PE4_TX_C_DP<8>")
		)
		(pad "2" smd rect
			(at 0.2667 0 270)
			(size 0.3048 0.381)
			(layers "F.Cu" "F.Mask" "F.Paste")
			(net "P5E_CPU1_PE4_TX_DP<8>")
		)
	)
)
